%FSTAX25Y25*%
%MOIN*%
%SFA1B1*%

%IPPOS*%
%ADD53R,0.028000X0.165000*%
%ADD54R,0.028000X0.126000*%
%ADD64R,0.057090X0.045280*%
%ADD66R,0.025200X0.026770*%
%ADD71R,0.045280X0.057090*%
%ADD72R,0.026770X0.025200*%
%ADD76R,0.082870X0.044090*%
%LNgrandmaster-1*%
%LPD*%
G54D53*
X0908661Y0514173D03*
X0786614D03*
X0782677D03*
X0814173D03*
X0810236D03*
X0869291D03*
X0900787D03*
X089685D03*
X0885039D03*
X0865354D03*
X0881102D03*
X0849606D03*
X0845669D03*
X0837795D03*
X0833858D03*
X081811D03*
X0794488D03*
X0798425D03*
X0802362D03*
X0806299D03*
X085748D03*
X0841732D03*
X0829921D03*
X0877165D03*
X0892913D03*
X0873228D03*
X0904724D03*
X0888976D03*
X0861417D03*
X0853543D03*
X0790551D03*
G54D54*
X077874Y0516123D03*
G54D64*
X08623Y0804643D03*
Y0797557D03*
G54D66*
X0834Y0536693D03*
Y0533307D03*
X0838D03*
Y0536693D03*
X08459D03*
Y0533307D03*
X08502D03*
Y0536693D03*
X08655Y0533307D03*
Y0536693D03*
X08695Y0533307D03*
Y0536693D03*
X0881Y0533307D03*
Y0536693D03*
X08845D03*
Y0533307D03*
X0897D03*
Y0536693D03*
X0901Y0533307D03*
Y0536693D03*
X08702Y0804093D03*
Y0800707D03*
G54D71*
X0831757Y07948D03*
X0838843D03*
G54D72*
X0834207Y07858D03*
X0837593D03*
G54D76*
X085Y0804678D03*
Y0820426D03*
Y0812552D03*
Y08283D03*
X08325Y0804678D03*
Y0812552D03*
Y0820426D03*
Y08283D03*
M02*